FILE_TYPE = CONNECTIVITY;
{Allegro Design Entry HDL 17.2-2016 S081 (4005846) 1/11/2022}
"PAGE_NUMBER" = 137;
0"NC";
1"GND\g";
2"GND\g";
3"GND\g";
4"GND\g";
5"P3V3\g";
6"P3V3\g";
7"P3V3\g";
8"P3V3\g";
9"GND\g";
10"GND\g";
11"P3V3\g";
12"P3V3\g";
13"SMB_SCM_10_R_SDA";
14"SMB_SCM_10_XLTR_R_SCL";
15"SMB_SCM_10_R_SCL";
16"SMB_SCM_11_XLTR_SCL";
17"SMB_SCM_10_XLTR_SDA";
18"SMB_SCM_11_XLTR_SCL";
19"PU_U96_EN";
20"SMB_SCM_11_R_SCL";
21"SMB_SCM_11_R_SDA";
22"P3V3\g";
23"P3V3_STBY\g";
24"P3V3\g";
25"P3V3_STBY\g";
26"SMB_SCM_10_XLTR_SCL";
27"SMB_SCM_10_XLTR_R_SDA";
28"SMB_SCM_11_XLTR_R_SDA";
29"SMB_SCM_11_XLTR_R_SCL";
30"SMB_SCM_11_XLTR_SDA";
31"SMB_SCM_10_XLTR_SCL";
32"PU_U5_EN";
33"SMB_SCM_10_XLTR_SDA";
34"SMB_SCM_11_XLTR_SDA";
%"UNIVERSAL_POWER"
"1","(-6400,2025)","2","pure_quanta_power","I160";
;
HDL_POWER"P3V3_STBY"
CDS_LIB"pure_quanta_power";
"A"25;
%"Q_CAP"
"1","(-6575,1750)","0","pure_quanta","I161";
;
LOCATION"C23"
$SEC"1"
CDS_SEC"1"
VALUE"0.1UF"
PACK_TYPE"0402"
MATERIAL"X7R"
VOLTAGE"25V"
TOLERANCE"10%"
CDS_LIB"pure_quanta"
PART_NUMBER"CH4104K1B00";
"B"
$PN"2"1;
"A"
$PN"1"25;
%"UNIVERSAL_GND"
"1","(-6575,1550)","0","pure_quanta_power","I162";
;
CDS_LIB"pure_quanta_power"
HDL_POWER"GND";
"A"1;
%"UNIVERSAL_GND"
"1","(-5250,1550)","0","pure_quanta_power","I163";
;
CDS_LIB"pure_quanta_power"
HDL_POWER"GND";
"A"2;
%"Q_CAP"
"1","(-5250,1750)","0","pure_quanta","I164";
;
LOCATION"C26"
$SEC"1"
CDS_SEC"1"
VOLTAGE"25V"
PACK_TYPE"0402"
MATERIAL"X7R"
VALUE"0.1UF"
TOLERANCE"10%"
CDS_LIB"pure_quanta"
PART_NUMBER"CH4104K1B00";
"B"
$PN"2"2;
"A"
$PN"1"24;
%"VCC_CORE"
"1","(-5325,2000)","0","pure_quanta_power","I165";
;
HDL_POWER"P3V3"
CDS_LIB"pure_quanta_power";
"A"24;
%"Q_RES"
"1","(-4025,1350)","0","pure_quanta","I186";
;
LOCATION"R1151"
$SEC"1"
CDS_SEC"1"
VALUE"0"
CDS_LIB"pure_quanta"
WATTAGE"1/16W"
MATERIAL"CHIP"
TOLERANCE"5%"
PART_NUMBER"CS00002JB38"
PACK_TYPE"0402LF";
"B"
$PN"2"26;
"A"
$PN"1"14;
%"Q_RES"
"1","(-4025,1250)","0","pure_quanta","I188";
;
LOCATION"R1152"
$SEC"1"
CDS_SEC"1"
VALUE"0"
CDS_LIB"pure_quanta"
WATTAGE"1/16W"
MATERIAL"CHIP"
TOLERANCE"5%"
PART_NUMBER"CS00002JB38"
PACK_TYPE"0402LF";
"B"
$PN"2"33;
"A"
$PN"1"27;
%"Q_RES"
"1","(-3950,-1375)","0","pure_quanta","I193";
;
LOCATION"R1153"
$SEC"1"
CDS_SEC"1"
VALUE"0"
CDS_LIB"pure_quanta"
WATTAGE"1/16W"
MATERIAL"CHIP"
TOLERANCE"5%"
PART_NUMBER"CS00002JB38"
PACK_TYPE"0402LF";
"B"
$PN"2"18;
"A"
$PN"1"29;
%"Q_RES"
"1","(-3950,-1475)","0","pure_quanta","I194";
;
LOCATION"R1154"
$SEC"1"
CDS_SEC"1"
VALUE"0"
CDS_LIB"pure_quanta"
WATTAGE"1/16W"
MATERIAL"CHIP"
TOLERANCE"5%"
PART_NUMBER"CS00002JB38"
PACK_TYPE"0402LF";
"B"
$PN"2"34;
"A"
$PN"1"28;
%"UNIVERSAL_POWER"
"1","(-6325,-700)","2","pure_quanta_power","I195";
;
HDL_POWER"P3V3_STBY"
CDS_LIB"pure_quanta_power";
"A"23;
%"Q_CAP"
"1","(-6500,-975)","0","pure_quanta","I196";
;
LOCATION"C611"
$SEC"1"
CDS_SEC"1"
MATERIAL"X7R"
PACK_TYPE"0402"
VALUE"0.1UF"
VOLTAGE"25V"
TOLERANCE"10%"
CDS_LIB"pure_quanta"
PART_NUMBER"CH4104K1B00";
"B"
$PN"2"3;
"A"
$PN"1"23;
%"UNIVERSAL_GND"
"1","(-6500,-1175)","0","pure_quanta_power","I197";
;
CDS_LIB"pure_quanta_power"
HDL_POWER"GND";
"A"3;
%"Q_CAP"
"1","(-5175,-975)","0","pure_quanta","I198";
;
LOCATION"C612"
$SEC"1"
CDS_SEC"1"
TOLERANCE"10%"
VOLTAGE"25V"
VALUE"0.1UF"
MATERIAL"X7R"
PACK_TYPE"0402"
CDS_LIB"pure_quanta"
PART_NUMBER"CH4104K1B00";
"B"
$PN"2"4;
"A"
$PN"1"22;
%"UNIVERSAL_GND"
"1","(-5175,-1175)","0","pure_quanta_power","I199";
;
CDS_LIB"pure_quanta_power"
HDL_POWER"GND";
"A"4;
%"VCC_CORE"
"1","(-5250,-725)","0","pure_quanta_power","I200";
;
HDL_POWER"P3V3"
CDS_LIB"pure_quanta_power";
"A"22;
%"VCC_CORE"
"1","(-1000,600)","0","pure_quanta_power","I201";
;
HDL_POWER"P3V3"
CDS_LIB"pure_quanta_power";
"A"5;
%"Q_RES"
"2","(-1000,350)","0","pure_quanta","I202";
;
LOCATION"R406"
$SEC"1"
CDS_SEC"1"
VALUE"4.7K"
TOLERANCE"5%"
WATTAGE"1/16W"
PACK_TYPE"0402LF"
MATERIAL"EMPTY"
CDS_LIB"pure_quanta"
PART_NUMBER"TMP_QCS24702JB38";
"A"
$PN"1"5;
"B"
$PN"2"30;
%"VCC_CORE"
"1","(-1275,600)","0","pure_quanta_power","I203";
;
HDL_POWER"P3V3"
CDS_LIB"pure_quanta_power";
"A"6;
%"Q_RES"
"2","(-1275,350)","0","pure_quanta","I204";
;
LOCATION"R368"
$SEC"1"
CDS_SEC"1"
PACK_TYPE"0402LF"
TOLERANCE"5%"
VALUE"4.7K"
WATTAGE"1/16W"
MATERIAL"EMPTY"
CDS_LIB"pure_quanta"
PART_NUMBER"TMP_QCS24702JB38";
"A"
$PN"1"6;
"B"
$PN"2"16;
%"VCC_CORE"
"1","(-1575,600)","0","pure_quanta_power","I205";
;
HDL_POWER"P3V3"
CDS_LIB"pure_quanta_power";
"A"7;
%"Q_RES"
"2","(-1575,350)","0","pure_quanta","I206";
;
LOCATION"R365"
$SEC"1"
CDS_SEC"1"
MATERIAL"EMPTY"
VALUE"4.7K"
PACK_TYPE"0402LF"
TOLERANCE"5%"
WATTAGE"1/16W"
CDS_LIB"pure_quanta"
PART_NUMBER"TMP_QCS24702JB38";
"A"
$PN"1"7;
"B"
$PN"2"17;
%"VCC_CORE"
"1","(-1900,600)","0","pure_quanta_power","I207";
;
HDL_POWER"P3V3"
CDS_LIB"pure_quanta_power";
"A"8;
%"Q_RES"
"2","(-1900,350)","0","pure_quanta","I208";
;
LOCATION"R361"
$SEC"1"
CDS_SEC"1"
TOLERANCE"5%"
WATTAGE"1/16W"
VALUE"4.7K"
PACK_TYPE"0402LF"
MATERIAL"EMPTY"
PART_NUMBER"TMP_QCS24702JB38"
CDS_LIB"pure_quanta";
"A"
$PN"1"8;
"B"
$PN"2"31;
%"PCA9617ADP"
"1","(-5900,1300)","0","pure_quanta","I213";
;
LOCATION"U5"
$SEC"1"
CDS_SEC"1"
MATERIAL"EMPTY"
PART_NUMBER"AL009617K02"
VALUE"PCA9617ADP"
PART_TYPE"SMLF"
CDS_LIB"pure_quanta"
NEEDS_NO_SIZE"TRUE"
CDS_LMAN_SYM_OUTLINE"-275,300,275,-300";
"GND"
$PN"4"9;
"SCLB"
$PN"7"14;
"SDAB"
$PN"6"27;
"SDAA"
$PN"3"13;
"SCLA"
$PN"2"15;
"VCCB"
$PN"8"24;
"VCCA"
$PN"1"25;
"EN"
$PN"5"32;
%"PCA9617ADP"
"1","(-5825,-1425)","0","pure_quanta","I214";
;
$LOCATION"U96"
CDS_LOCATION"U96"
$SEC"1"
CDS_SEC"1"
MATERIAL"EMPTY"
PART_TYPE"SMLF"
VALUE"PCA9617ADP"
PART_NUMBER"AL009617K02"
CDS_LIB"pure_quanta"
NEEDS_NO_SIZE"TRUE"
CDS_LMAN_SYM_OUTLINE"-275,300,275,-300";
"GND"
$PN"4"10;
"SCLB"
$PN"7"29;
"SDAB"
$PN"6"28;
"SDAA"
$PN"3"21;
"SCLA"
$PN"2"20;
"VCCB"
$PN"8"22;
"VCCA"
$PN"1"23;
"EN"
$PN"5"19;
%"UNIVERSAL_GND"
"1","(-6400,950)","0","pure_quanta_power","I215";
;
CDS_LIB"pure_quanta_power"
HDL_POWER"GND";
"A"9;
%"UNIVERSAL_GND"
"1","(-6350,-1750)","0","pure_quanta_power","I216";
;
CDS_LIB"pure_quanta_power"
HDL_POWER"GND";
"A"10;
%"Q_RES"
"1","(-5900,2375)","0","pure_quanta","I217";
;
LOCATION"R789"
$SEC"1"
CDS_SEC"1"
MATERIAL"CHIP"
VALUE"0"
PACK_TYPE"0402LF"
PART_NUMBER"CS00002JB38"
TOLERANCE"5%"
WATTAGE"1/16W"
CDS_LIB"pure_quanta";
"B"
$PN"2"14;
"A"
$PN"1"15;
%"Q_RES"
"1","(-5900,2325)","0","pure_quanta","I218";
;
LOCATION"R790"
$SEC"1"
CDS_SEC"1"
MATERIAL"CHIP"
VALUE"0"
CDS_LIB"pure_quanta"
WATTAGE"1/16W"
TOLERANCE"5%"
PART_NUMBER"CS00002JB38"
PACK_TYPE"0402LF";
"B"
$PN"2"27;
"A"
$PN"1"13;
%"Q_RES"
"1","(-5825,-300)","0","pure_quanta","I219";
;
LOCATION"R791"
$SEC"1"
CDS_SEC"1"
MATERIAL"CHIP"
VALUE"0"
CDS_LIB"pure_quanta"
WATTAGE"1/16W"
TOLERANCE"5%"
PART_NUMBER"CS00002JB38"
PACK_TYPE"0402LF";
"B"
$PN"2"29;
"A"
$PN"1"20;
%"Q_RES"
"1","(-5825,-350)","0","pure_quanta","I220";
;
LOCATION"R792"
$SEC"1"
CDS_SEC"1"
MATERIAL"CHIP"
VALUE"0"
CDS_LIB"pure_quanta"
WATTAGE"1/16W"
TOLERANCE"5%"
PART_NUMBER"CS00002JB38"
PACK_TYPE"0402LF";
"B"
$PN"2"28;
"A"
$PN"1"21;
%"Q_RES"
"2","(-4150,775)","0","pure_quanta","I221";
;
$LOCATION"R78"
CDS_LOCATION"R78"
$SEC"1"
CDS_SEC"1"
WATTAGE"1/16W"
TOLERANCE"5%"
MATERIAL"EMPTY"
PACK_TYPE"0402LF"
VALUE"4.7K"
PART_NUMBER"TMP_QCS24702JB38"
CDS_LIB"pure_quanta";
"A"
$PN"1"11;
"B"
$PN"2"32;
%"VCC_CORE"
"1","(-4150,1050)","0","pure_quanta_power","I222";
;
HDL_POWER"P3V3"
CDS_LIB"pure_quanta_power";
"A"11;
%"VCC_CORE"
"1","(-4025,-1700)","0","pure_quanta_power","I223";
;
HDL_POWER"P3V3"
CDS_LIB"pure_quanta_power";
"A"12;
%"Q_RES"
"2","(-4025,-1975)","0","pure_quanta","I224";
;
$LOCATION"R200"
CDS_LOCATION"R200"
$SEC"1"
CDS_SEC"1"
PACK_TYPE"0402LF"
WATTAGE"1/16W"
MATERIAL"EMPTY"
TOLERANCE"5%"
VALUE"4.7K"
CDS_LIB"pure_quanta"
PART_NUMBER"TMP_QCS24702JB38";
"A"
$PN"1"12;
"B"
$PN"2"19;
END.
